(kicad_pcb
	(version 20260206)
	(generator "pcbnew")
	(generator_version "10.0")
	(general
		(thickness 1.6)
		(legacy_teardrops no)
	)
	(paper "A4")
	(title_block
		(title "03242023_DA0F0TMBIJ0_F0T_Motherboard_J_brd_V01_OCP.brd")
		(comment 1 "Grand Teton / footprints 1567-1572 of 6105")
	)
	(layers
		(0 "F.Cu" signal "TOP")
		(4 "In1.Cu" signal "GND")
		(6 "In2.Cu" signal "IN1")
		(8 "In3.Cu" signal "GND1")
		(10 "In4.Cu" signal "IN2")
		(12 "In5.Cu" signal "GND2")
		(14 "In6.Cu" signal "IN3")
		(16 "In7.Cu" signal "GND3")
		(18 "In8.Cu" signal "VCC")
		(20 "In9.Cu" signal "VCC1")
		(22 "In10.Cu" signal "GND4")
		(24 "In11.Cu" signal "IN4")
		(26 "In12.Cu" signal "GND5")
		(28 "In13.Cu" signal "IN5")
		(30 "In14.Cu" signal "GND6")
		(32 "In15.Cu" signal "IN6")
		(34 "In16.Cu" signal "GND7")
		(2 "B.Cu" signal "BOTTOM")
		(9 "F.Adhes" user "F.Adhesive")
		(11 "B.Adhes" user "B.Adhesive")
		(13 "F.Paste" user "Package Geometry/Pastemask Top")
		(15 "B.Paste" user "Package Geometry/Pastemask Bottom")
		(5 "F.SilkS" user "Ref Des/Silkscreen Top")
		(7 "B.SilkS" user "Ref Des/Silkscreen Bottom")
		(1 "F.Mask" user "Board Geometry/Soldermask Top")
		(3 "B.Mask" user "Board Geometry/Soldermask Bottom")
		(17 "Dwgs.User" user "User.Drawings")
		(19 "Cmts.User" user "User.Comments")
		(21 "Eco1.User" user "User.Eco1")
		(23 "Eco2.User" user "User.Eco2")
		(25 "Edge.Cuts" user "Board Geometry/Outline")
		(27 "Margin" user)
		(31 "F.CrtYd" user "Package Geometry/Place Bound Top")
		(29 "B.CrtYd" user "Package Geometry/Place Bound Bottom")
		(35 "F.Fab" user "Ref Des/Assembly Top")
		(33 "B.Fab" user "Ref Des/Assembly Bottom")
	)
	(footprint ""
		(layer "F.Cu")
		(at 226.733608 -401.775422 180)
		(property "Reference" "PR3987"
			(at 0 0 180)
			(layer "F.SilkS")
			(hide yes)
			(effects
				(font
					(size 1.27 1.27)
				)
			)
		)
		(property "Value" ""
			(at 0 0 180)
			(layer "F.Fab")
			(effects
				(font
					(size 1.27 1.27)
				)
			)
		)
		(duplicate_pad_numbers_are_jumpers no)
		(fp_line
			(start 0.7874 0.4064)
			(end -0.7874 0.4064)
			(stroke
				(width 0.1524)
				(type default)
			)
			(layer "F.SilkS")
		)
		(fp_line
			(start 0.7874 -0.4064)
			(end 0.7874 0.4064)
			(stroke
				(width 0.1524)
				(type default)
			)
			(layer "F.SilkS")
		)
		(fp_line
			(start -0.7874 0.4064)
			(end -0.7874 -0.4064)
			(stroke
				(width 0.1524)
				(type default)
			)
			(layer "F.SilkS")
		)
		(fp_line
			(start -0.7874 -0.4064)
			(end 0.7874 -0.4064)
			(stroke
				(width 0.1524)
				(type default)
			)
			(layer "F.SilkS")
		)
		(fp_line
			(start 0.67945 0.3048)
			(end 0.120396 0.3048)
			(stroke
				(width 0.1)
				(type default)
			)
			(layer "F.Fab")
		)
		(fp_line
			(start 0.67945 -0.3048)
			(end 0.67945 0.3048)
			(stroke
				(width 0.1)
				(type default)
			)
			(layer "F.Fab")
		)
		(fp_line
			(start 0.12065 -0.2794)
			(end 0.12065 -0.3048)
			(stroke
				(width 0.1)
				(type default)
			)
			(layer "F.Fab")
		)
		(fp_line
			(start 0.12065 -0.3048)
			(end 0.67945 -0.3048)
			(stroke
				(width 0.1)
				(type default)
			)
			(layer "F.Fab")
		)
		(fp_line
			(start 0.120396 0.3048)
			(end 0.120396 0.2794)
			(stroke
				(width 0.1)
				(type default)
			)
			(layer "F.Fab")
		)
		(fp_line
			(start 0.120396 0.2794)
			(end -0.12065 0.2794)
			(stroke
				(width 0.1)
				(type default)
			)
			(layer "F.Fab")
		)
		(fp_line
			(start -0.12065 0.3048)
			(end -0.67945 0.3048)
			(stroke
				(width 0.1)
				(type default)
			)
			(layer "F.Fab")
		)
		(fp_line
			(start -0.12065 0.2794)
			(end -0.12065 0.3048)
			(stroke
				(width 0.1)
				(type default)
			)
			(layer "F.Fab")
		)
		(fp_line
			(start -0.12065 -0.2794)
			(end 0.12065 -0.2794)
			(stroke
				(width 0.1)
				(type default)
			)
			(layer "F.Fab")
		)
		(fp_line
			(start -0.12065 -0.305054)
			(end -0.12065 -0.2794)
			(stroke
				(width 0.1)
				(type default)
			)
			(layer "F.Fab")
		)
		(fp_line
			(start -0.67945 0.3048)
			(end -0.67945 -0.305054)
			(stroke
				(width 0.1)
				(type default)
			)
			(layer "F.Fab")
		)
		(fp_line
			(start -0.67945 -0.305054)
			(end -0.12065 -0.305054)
			(stroke
				(width 0.1)
				(type default)
			)
			(layer "F.Fab")
		)
		(pad "1" smd circle
			(at -0.40005 0 180)
			(size 0 0)
			(layers "F.Cu" "F.Mask" "F.Paste")
			(net "HSC_CS_4")
		)
		(pad "2" smd circle
			(at 0.40005 0 180)
			(size 0 0)
			(layers "F.Cu" "F.Mask" "F.Paste")
			(net "AGND_HSC")
		)
	)
	(footprint ""
		(layer "F.Cu")
		(at 423.56278 -106.129328 90)
		(property "Reference" "PC2163"
			(at 0 0 90)
			(layer "F.SilkS")
			(hide yes)
			(effects
				(font
					(size 1.27 1.27)
				)
			)
		)
		(property "Value" ""
			(at 0 0 90)
			(layer "F.Fab")
			(effects
				(font
					(size 1.27 1.27)
				)
			)
		)
		(duplicate_pad_numbers_are_jumpers no)
		(fp_line
			(start 1.524 -0.762)
			(end 1.524 0.762)
			(stroke
				(width 0.1524)
				(type default)
			)
			(layer "F.SilkS")
		)
		(fp_line
			(start -1.524 -0.762)
			(end 1.524 -0.762)
			(stroke
				(width 0.1524)
				(type default)
			)
			(layer "F.SilkS")
		)
		(fp_line
			(start 1.524 0.762)
			(end -1.524 0.762)
			(stroke
				(width 0.1524)
				(type default)
			)
			(layer "F.SilkS")
		)
		(fp_line
			(start -1.524 0.762)
			(end -1.524 -0.762)
			(stroke
				(width 0.1524)
				(type default)
			)
			(layer "F.SilkS")
		)
		(fp_line
			(start 1.1049 -0.724916)
			(end -1.1049 -0.724916)
			(stroke
				(width 0.1)
				(type default)
			)
			(layer "F.Fab")
		)
		(fp_line
			(start -1.1049 -0.724916)
			(end -1.1049 0.724916)
			(stroke
				(width 0.1)
				(type default)
			)
			(layer "F.Fab")
		)
		(fp_line
			(start 1.1049 0.724916)
			(end 1.1049 -0.724916)
			(stroke
				(width 0.1)
				(type default)
			)
			(layer "F.Fab")
		)
		(fp_line
			(start -1.1049 0.724916)
			(end 1.1049 0.724916)
			(stroke
				(width 0.1)
				(type default)
			)
			(layer "F.Fab")
		)
		(pad "1" smd rect
			(at -0.889 0 270)
			(size 1.016 1.27)
			(layers "F.Cu" "F.Mask" "F.Paste")
			(net "P3V3_OCP_SFF_R")
		)
		(pad "2" smd rect
			(at 0.889 0 270)
			(size 1.016 1.27)
			(layers "F.Cu" "F.Mask" "F.Paste")
			(net "GND")
		)
	)
	(footprint ""
		(layer "F.Cu")
		(at 219.79128 -111.115348 180)
		(property "Reference" "D0"
			(at -2.3876 -0.581152 0)
			(unlocked yes)
			(layer "F.SilkS")
			(effects
				(font
					(size 0.7874 0.5842)
					(thickness 0.1524)
				)
				(justify left)
			)
		)
		(property "Value" ""
			(at 0 0 180)
			(layer "F.Fab")
			(effects
				(font
					(size 1.27 1.27)
				)
			)
		)
		(duplicate_pad_numbers_are_jumpers no)
		(fp_line
			(start 1.16078 0.4826)
			(end -0.64008 0.4826)
			(stroke
				(width 0.1524)
				(type default)
			)
			(layer "F.SilkS")
		)
		(fp_line
			(start 1.16078 -0.4826)
			(end 1.16078 0.4826)
			(stroke
				(width 0.1524)
				(type default)
			)
			(layer "F.SilkS")
		)
		(fp_line
			(start 1.03378 0.4826)
			(end -0.79248 0.4826)
			(stroke
				(width 0.1524)
				(type default)
			)
			(layer "F.SilkS")
		)
		(fp_line
			(start 1.03378 -0.4826)
			(end 1.03378 0.4826)
			(stroke
				(width 0.1524)
				(type default)
			)
			(layer "F.SilkS")
		)
		(fp_line
			(start 0.90678 0.4826)
			(end -0.90678 0.4826)
			(stroke
				(width 0.1524)
				(type default)
			)
			(layer "F.SilkS")
		)
		(fp_line
			(start 0.90678 -0.4826)
			(end 0.90678 0.4826)
			(stroke
				(width 0.1524)
				(type default)
			)
			(layer "F.SilkS")
		)
		(fp_line
			(start -0.64008 -0.4826)
			(end 1.16078 -0.4826)
			(stroke
				(width 0.1524)
				(type default)
			)
			(layer "F.SilkS")
		)
		(fp_line
			(start -0.79248 -0.4826)
			(end 1.03378 -0.4826)
			(stroke
				(width 0.1524)
				(type default)
			)
			(layer "F.SilkS")
		)
		(fp_line
			(start -0.89408 -0.4826)
			(end 0.90678 -0.4826)
			(stroke
				(width 0.1524)
				(type default)
			)
			(layer "F.SilkS")
		)
		(fp_line
			(start -0.90678 0.4826)
			(end -0.90678 -0.4699)
			(stroke
				(width 0.1524)
				(type default)
			)
			(layer "F.SilkS")
		)
		(fp_line
			(start 0.499872 0.249936)
			(end -0.499872 0.249936)
			(stroke
				(width 0.1)
				(type default)
			)
			(layer "F.Fab")
		)
		(fp_line
			(start 0.499872 -0.249936)
			(end 0.499872 0.249936)
			(stroke
				(width 0.1)
				(type default)
			)
			(layer "F.Fab")
		)
		(fp_line
			(start -0.499872 0.249936)
			(end -0.499872 -0.249936)
			(stroke
				(width 0.1)
				(type default)
			)
			(layer "F.Fab")
		)
		(fp_line
			(start -0.499872 -0.249936)
			(end 0.499872 -0.249936)
			(stroke
				(width 0.1)
				(type default)
			)
			(layer "F.Fab")
		)
		(pad "A" smd rect
			(at -0.47498 0 180)
			(size 0.6096 0.7112)
			(layers "F.Cu" "F.Mask" "F.Paste")
			(net "PU_PLD_HEARTBEAT_LVC3")
		)
		(pad "C" smd rect
			(at 0.47498 0 180)
			(size 0.6096 0.7112)
			(layers "F.Cu" "F.Mask" "F.Paste")
			(net "FM_PLD_HEARTBEAT_LVC3_D")
		)
	)
	(footprint ""
		(layer "F.Cu")
		(at 309.522622 -39.106348 180)
		(property "Reference" "R453"
			(at 0 0 180)
			(layer "F.SilkS")
			(hide yes)
			(effects
				(font
					(size 1.27 1.27)
				)
			)
		)
		(property "Value" ""
			(at 0 0 180)
			(layer "F.Fab")
			(effects
				(font
					(size 1.27 1.27)
				)
			)
		)
		(duplicate_pad_numbers_are_jumpers no)
		(fp_line
			(start 0.7874 0.4064)
			(end -0.7874 0.4064)
			(stroke
				(width 0.1524)
				(type default)
			)
			(layer "F.SilkS")
		)
		(fp_line
			(start 0.7874 -0.4064)
			(end 0.7874 0.4064)
			(stroke
				(width 0.1524)
				(type default)
			)
			(layer "F.SilkS")
		)
		(fp_line
			(start -0.7874 0.4064)
			(end -0.7874 -0.4064)
			(stroke
				(width 0.1524)
				(type default)
			)
			(layer "F.SilkS")
		)
		(fp_line
			(start -0.7874 -0.4064)
			(end 0.7874 -0.4064)
			(stroke
				(width 0.1524)
				(type default)
			)
			(layer "F.SilkS")
		)
		(fp_line
			(start 0.67945 0.3048)
			(end 0.120396 0.3048)
			(stroke
				(width 0.1)
				(type default)
			)
			(layer "F.Fab")
		)
		(fp_line
			(start 0.67945 -0.3048)
			(end 0.67945 0.3048)
			(stroke
				(width 0.1)
				(type default)
			)
			(layer "F.Fab")
		)
		(fp_line
			(start 0.12065 -0.2794)
			(end 0.12065 -0.3048)
			(stroke
				(width 0.1)
				(type default)
			)
			(layer "F.Fab")
		)
		(fp_line
			(start 0.12065 -0.3048)
			(end 0.67945 -0.3048)
			(stroke
				(width 0.1)
				(type default)
			)
			(layer "F.Fab")
		)
		(fp_line
			(start 0.120396 0.3048)
			(end 0.120396 0.2794)
			(stroke
				(width 0.1)
				(type default)
			)
			(layer "F.Fab")
		)
		(fp_line
			(start 0.120396 0.2794)
			(end -0.12065 0.2794)
			(stroke
				(width 0.1)
				(type default)
			)
			(layer "F.Fab")
		)
		(fp_line
			(start -0.12065 0.3048)
			(end -0.67945 0.3048)
			(stroke
				(width 0.1)
				(type default)
			)
			(layer "F.Fab")
		)
		(fp_line
			(start -0.12065 0.2794)
			(end -0.12065 0.3048)
			(stroke
				(width 0.1)
				(type default)
			)
			(layer "F.Fab")
		)
		(fp_line
			(start -0.12065 -0.2794)
			(end 0.12065 -0.2794)
			(stroke
				(width 0.1)
				(type default)
			)
			(layer "F.Fab")
		)
		(fp_line
			(start -0.12065 -0.305054)
			(end -0.12065 -0.2794)
			(stroke
				(width 0.1)
				(type default)
			)
			(layer "F.Fab")
		)
		(fp_line
			(start -0.67945 0.3048)
			(end -0.67945 -0.305054)
			(stroke
				(width 0.1)
				(type default)
			)
			(layer "F.Fab")
		)
		(fp_line
			(start -0.67945 -0.305054)
			(end -0.12065 -0.305054)
			(stroke
				(width 0.1)
				(type default)
			)
			(layer "F.Fab")
		)
		(pad "1" smd circle
			(at -0.40005 0 180)
			(size 0 0)
			(layers "F.Cu" "F.Mask" "F.Paste")
			(net "P3V3_AUX")
		)
		(pad "2" smd circle
			(at 0.40005 0 180)
			(size 0 0)
			(layers "F.Cu" "F.Mask" "F.Paste")
			(net "PU_LAN_WAKE_N")
		)
	)
	(footprint ""
		(layer "F.Cu")
		(at 434.805328 -19.614134 -90)
		(property "Reference" "R1929"
			(at 0 0 270)
			(layer "F.SilkS")
			(hide yes)
			(effects
				(font
					(size 1.27 1.27)
				)
			)
		)
		(property "Value" ""
			(at 0 0 270)
			(layer "F.Fab")
			(effects
				(font
					(size 1.27 1.27)
				)
			)
		)
		(duplicate_pad_numbers_are_jumpers no)
		(fp_line
			(start -0.7874 0.4064)
			(end -0.7874 -0.4064)
			(stroke
				(width 0.1524)
				(type default)
			)
			(layer "F.SilkS")
		)
		(fp_line
			(start 0.7874 0.4064)
			(end -0.7874 0.4064)
			(stroke
				(width 0.1524)
				(type default)
			)
			(layer "F.SilkS")
		)
		(fp_line
			(start -0.7874 -0.4064)
			(end 0.7874 -0.4064)
			(stroke
				(width 0.1524)
				(type default)
			)
			(layer "F.SilkS")
		)
		(fp_line
			(start 0.7874 -0.4064)
			(end 0.7874 0.4064)
			(stroke
				(width 0.1524)
				(type default)
			)
			(layer "F.SilkS")
		)
		(fp_line
			(start -0.67945 0.3048)
			(end -0.67945 -0.305054)
			(stroke
				(width 0.1)
				(type default)
			)
			(layer "F.Fab")
		)
		(fp_line
			(start -0.12065 0.3048)
			(end -0.67945 0.3048)
			(stroke
				(width 0.1)
				(type default)
			)
			(layer "F.Fab")
		)
		(fp_line
			(start 0.120396 0.3048)
			(end 0.120396 0.2794)
			(stroke
				(width 0.1)
				(type default)
			)
			(layer "F.Fab")
		)
		(fp_line
			(start 0.67945 0.3048)
			(end 0.120396 0.3048)
			(stroke
				(width 0.1)
				(type default)
			)
			(layer "F.Fab")
		)
		(fp_line
			(start -0.12065 0.2794)
			(end -0.12065 0.3048)
			(stroke
				(width 0.1)
				(type default)
			)
			(layer "F.Fab")
		)
		(fp_line
			(start 0.120396 0.2794)
			(end -0.12065 0.2794)
			(stroke
				(width 0.1)
				(type default)
			)
			(layer "F.Fab")
		)
		(fp_line
			(start -0.12065 -0.2794)
			(end 0.12065 -0.2794)
			(stroke
				(width 0.1)
				(type default)
			)
			(layer "F.Fab")
		)
		(fp_line
			(start 0.12065 -0.2794)
			(end 0.12065 -0.3048)
			(stroke
				(width 0.1)
				(type default)
			)
			(layer "F.Fab")
		)
		(fp_line
			(start 0.12065 -0.3048)
			(end 0.67945 -0.3048)
			(stroke
				(width 0.1)
				(type default)
			)
			(layer "F.Fab")
		)
		(fp_line
			(start 0.67945 -0.3048)
			(end 0.67945 0.3048)
			(stroke
				(width 0.1)
				(type default)
			)
			(layer "F.Fab")
		)
		(fp_line
			(start -0.67945 -0.305054)
			(end -0.12065 -0.305054)
			(stroke
				(width 0.1)
				(type default)
			)
			(layer "F.Fab")
		)
		(fp_line
			(start -0.12065 -0.305054)
			(end -0.12065 -0.2794)
			(stroke
				(width 0.1)
				(type default)
			)
			(layer "F.Fab")
		)
		(pad "1" smd circle
			(at -0.40005 0 270)
			(size 0 0)
			(layers "F.Cu" "F.Mask" "F.Paste")
			(net "GND")
		)
		(pad "2" smd circle
			(at 0.40005 0 270)
			(size 0 0)
			(layers "F.Cu" "F.Mask" "F.Paste")
			(net "OCP_SFF_AUX_PWR_EN")
		)
	)
	(footprint ""
		(layer "F.Cu")
		(at 309.523638 -37.822886 180)
		(property "Reference" "R4101"
			(at 0 0 180)
			(layer "F.SilkS")
			(hide yes)
			(effects
				(font
					(size 1.27 1.27)
				)
			)
		)
		(property "Value" ""
			(at 0 0 180)
			(layer "F.Fab")
			(effects
				(font
					(size 1.27 1.27)
				)
			)
		)
		(duplicate_pad_numbers_are_jumpers no)
		(fp_line
			(start 0.7874 0.4064)
			(end -0.7874 0.4064)
			(stroke
				(width 0.1524)
				(type default)
			)
			(layer "F.SilkS")
		)
		(fp_line
			(start 0.7874 -0.4064)
			(end 0.7874 0.4064)
			(stroke
				(width 0.1524)
				(type default)
			)
			(layer "F.SilkS")
		)
		(fp_line
			(start -0.7874 0.4064)
			(end -0.7874 -0.4064)
			(stroke
				(width 0.1524)
				(type default)
			)
			(layer "F.SilkS")
		)
		(fp_line
			(start -0.7874 -0.4064)
			(end 0.7874 -0.4064)
			(stroke
				(width 0.1524)
				(type default)
			)
			(layer "F.SilkS")
		)
		(fp_line
			(start 0.67945 0.3048)
			(end 0.120396 0.3048)
			(stroke
				(width 0.1)
				(type default)
			)
			(layer "F.Fab")
		)
		(fp_line
			(start 0.67945 -0.3048)
			(end 0.67945 0.3048)
			(stroke
				(width 0.1)
				(type default)
			)
			(layer "F.Fab")
		)
		(fp_line
			(start 0.12065 -0.2794)
			(end 0.12065 -0.3048)
			(stroke
				(width 0.1)
				(type default)
			)
			(layer "F.Fab")
		)
		(fp_line
			(start 0.12065 -0.3048)
			(end 0.67945 -0.3048)
			(stroke
				(width 0.1)
				(type default)
			)
			(layer "F.Fab")
		)
		(fp_line
			(start 0.120396 0.3048)
			(end 0.120396 0.2794)
			(stroke
				(width 0.1)
				(type default)
			)
			(layer "F.Fab")
		)
		(fp_line
			(start 0.120396 0.2794)
			(end -0.12065 0.2794)
			(stroke
				(width 0.1)
				(type default)
			)
			(layer "F.Fab")
		)
		(fp_line
			(start -0.12065 0.3048)
			(end -0.67945 0.3048)
			(stroke
				(width 0.1)
				(type default)
			)
			(layer "F.Fab")
		)
		(fp_line
			(start -0.12065 0.2794)
			(end -0.12065 0.3048)
			(stroke
				(width 0.1)
				(type default)
			)
			(layer "F.Fab")
		)
		(fp_line
			(start -0.12065 -0.2794)
			(end 0.12065 -0.2794)
			(stroke
				(width 0.1)
				(type default)
			)
			(layer "F.Fab")
		)
		(fp_line
			(start -0.12065 -0.305054)
			(end -0.12065 -0.2794)
			(stroke
				(width 0.1)
				(type default)
			)
			(layer "F.Fab")
		)
		(fp_line
			(start -0.67945 0.3048)
			(end -0.67945 -0.305054)
			(stroke
				(width 0.1)
				(type default)
			)
			(layer "F.Fab")
		)
		(fp_line
			(start -0.67945 -0.305054)
			(end -0.12065 -0.305054)
			(stroke
				(width 0.1)
				(type default)
			)
			(layer "F.Fab")
		)
		(pad "1" smd circle
			(at -0.40005 0 180)
			(size 0 0)
			(layers "F.Cu" "F.Mask" "F.Paste")
			(net "PD_PCH_GPPC_C9")
		)
		(pad "2" smd circle
			(at 0.40005 0 180)
			(size 0 0)
			(layers "F.Cu" "F.Mask" "F.Paste")
			(net "GND")
		)
	)
)
